(kicad_pcb
	(version 20260206)
	(generator "pcbnew")
	(generator_version "10.0")
	(general
		(thickness 1.6)
		(legacy_teardrops no)
	)
	(paper "A4")
	(title_block
		(title "01162023_DA0F0TEBIF0_F0T_Expander_BD_F_brd_V02_OCP.brd")
		(comment 1 "Grand Teton / footprints 4408-4413 of 9728")
	)
	(layers
		(0 "F.Cu" signal "TOP")
		(4 "In1.Cu" signal "GND")
		(6 "In2.Cu" signal "VCC")
		(8 "In3.Cu" signal "VCC1")
		(10 "In4.Cu" signal "GND1")
		(12 "In5.Cu" signal "IN1")
		(14 "In6.Cu" signal "GND2")
		(16 "In7.Cu" signal "IN2")
		(18 "In8.Cu" signal "GND3")
		(20 "In9.Cu" signal "IN3")
		(22 "In10.Cu" signal "GND4")
		(24 "In11.Cu" signal "IN4")
		(26 "In12.Cu" signal "GND5")
		(28 "In13.Cu" signal "IN5")
		(30 "In14.Cu" signal "GND6")
		(32 "In15.Cu" signal "IN6")
		(34 "In16.Cu" signal "GND7")
		(2 "B.Cu" signal "BOTTOM")
		(9 "F.Adhes" user "F.Adhesive")
		(11 "B.Adhes" user "B.Adhesive")
		(13 "F.Paste" user "Package Geometry/Pastemask Top")
		(15 "B.Paste" user "Package Geometry/Pastemask Bottom")
		(5 "F.SilkS" user "Ref Des/Silkscreen Top")
		(7 "B.SilkS" user "Ref Des/Silkscreen Bottom")
		(1 "F.Mask" user "Board Geometry/Soldermask Top")
		(3 "B.Mask" user "Board Geometry/Soldermask Bottom")
		(17 "Dwgs.User" user "User.Drawings")
		(19 "Cmts.User" user "User.Comments")
		(21 "Eco1.User" user "User.Eco1")
		(23 "Eco2.User" user "User.Eco2")
		(25 "Edge.Cuts" user "Board Geometry/Outline")
		(27 "Margin" user)
		(31 "F.CrtYd" user "Package Geometry/Place Bound Top")
		(29 "B.CrtYd" user "Package Geometry/Place Bound Bottom")
		(35 "F.Fab" user "Ref Des/Assembly Top")
		(33 "B.Fab" user "Ref Des/Assembly Bottom")
	)
	(footprint ""
		(layer "F.Cu")
		(at 222.619316 -122.758962)
		(property "Reference" "Q215"
			(at 0.486918 -1.943862 0)
			(unlocked yes)
			(layer "F.SilkS")
			(effects
				(font
					(size 0.7874 0.5842)
					(thickness 0.1524)
				)
			)
		)
		(property "Value" ""
			(at 0 0 0)
			(layer "F.Fab")
			(effects
				(font
					(size 1.27 1.27)
				)
			)
		)
		(duplicate_pad_numbers_are_jumpers no)
		(fp_line
			(start -1.376172 -1.199896)
			(end -0.508 -1.199896)
			(stroke
				(width 0.1524)
				(type default)
			)
			(layer "F.SilkS")
		)
		(fp_line
			(start -1.376172 1.199896)
			(end -1.376172 -1.199896)
			(stroke
				(width 0.1524)
				(type default)
			)
			(layer "F.SilkS")
		)
		(fp_line
			(start -0.508 -1.199896)
			(end 0 -0.762)
			(stroke
				(width 0.1524)
				(type default)
			)
			(layer "F.SilkS")
		)
		(fp_line
			(start 0 -0.762)
			(end 0.508 -1.199896)
			(stroke
				(width 0.1524)
				(type default)
			)
			(layer "F.SilkS")
		)
		(fp_line
			(start 0.508 -1.199896)
			(end 1.376172 -1.199896)
			(stroke
				(width 0.1524)
				(type default)
			)
			(layer "F.SilkS")
		)
		(fp_line
			(start 1.376172 -1.199896)
			(end 1.376172 1.199896)
			(stroke
				(width 0.1524)
				(type default)
			)
			(layer "F.SilkS")
		)
		(fp_line
			(start 1.376172 1.199896)
			(end -1.376172 1.199896)
			(stroke
				(width 0.1524)
				(type default)
			)
			(layer "F.SilkS")
		)
		(fp_poly
			(pts
				(xy -1.130554 -1.321308) (xy -1.400048 -2.129536) (xy -1.938782 -1.590548)
			)
			(stroke
				(width 0)
				(type default)
			)
			(fill yes)
			(layer "F.SilkS")
		)
		(fp_line
			(start -0.674878 -1.100074)
			(end 0.674878 -1.100074)
			(stroke
				(width 0.1)
				(type default)
			)
			(layer "F.Fab")
		)
		(fp_line
			(start -0.674878 1.100074)
			(end -0.674878 -1.100074)
			(stroke
				(width 0.1)
				(type default)
			)
			(layer "F.Fab")
		)
		(fp_line
			(start 0.674878 -1.100074)
			(end 0.674878 1.100074)
			(stroke
				(width 0.1)
				(type default)
			)
			(layer "F.Fab")
		)
		(fp_line
			(start 0.674878 1.100074)
			(end -0.674878 1.100074)
			(stroke
				(width 0.1)
				(type default)
			)
			(layer "F.Fab")
		)
		(fp_poly
			(pts
				(xy -1.4605 -0.7493) (xy -2.2225 -1.1303) (xy -2.2225 -0.3683)
			)
			(stroke
				(width 0)
				(type default)
			)
			(fill yes)
			(layer "F.Fab")
		)
		(pad "1" smd rect
			(at -0.899922 -0.750062 270)
			(size 0.6096 0.6096)
			(layers "F.Cu" "F.Mask" "F.Paste")
			(net "GND")
		)
		(pad "2" smd rect
			(at -0.899922 0 270)
			(size 0.4064 0.6096)
			(layers "F.Cu" "F.Mask" "F.Paste")
			(net "P3V3_NIC3_PG_G1")
		)
		(pad "3" smd rect
			(at -0.899922 0.750062 270)
			(size 0.6096 0.6096)
			(layers "F.Cu" "F.Mask" "F.Paste")
			(net "PWRGD_P3V3_NIC3_D")
		)
		(pad "4" smd rect
			(at 0.899922 0.750062 270)
			(size 0.6096 0.6096)
			(layers "F.Cu" "F.Mask" "F.Paste")
			(net "GND")
		)
		(pad "5" smd rect
			(at 0.899922 0 270)
			(size 0.4064 0.6096)
			(layers "F.Cu" "F.Mask" "F.Paste")
			(net "P3V3_NIC3_PG_G2")
		)
		(pad "6" smd rect
			(at 0.899922 -0.750062 270)
			(size 0.6096 0.6096)
			(layers "F.Cu" "F.Mask" "F.Paste")
			(net "P3V3_NIC3_PG_G2")
		)
	)
	(footprint ""
		(layer "F.Cu")
		(at 149.080728 -381.428498)
		(property "Reference" "R1842"
			(at 0 0 0)
			(layer "F.SilkS")
			(hide yes)
			(effects
				(font
					(size 1.27 1.27)
				)
			)
		)
		(property "Value" ""
			(at 0 0 0)
			(layer "F.Fab")
			(effects
				(font
					(size 1.27 1.27)
				)
			)
		)
		(duplicate_pad_numbers_are_jumpers no)
		(fp_line
			(start -0.7874 -0.4064)
			(end 0.7874 -0.4064)
			(stroke
				(width 0.1524)
				(type default)
			)
			(layer "F.SilkS")
		)
		(fp_line
			(start -0.7874 0.4064)
			(end -0.7874 -0.4064)
			(stroke
				(width 0.1524)
				(type default)
			)
			(layer "F.SilkS")
		)
		(fp_line
			(start 0.7874 -0.4064)
			(end 0.7874 0.4064)
			(stroke
				(width 0.1524)
				(type default)
			)
			(layer "F.SilkS")
		)
		(fp_line
			(start 0.7874 0.4064)
			(end -0.7874 0.4064)
			(stroke
				(width 0.1524)
				(type default)
			)
			(layer "F.SilkS")
		)
		(fp_line
			(start -0.67945 -0.305054)
			(end -0.12065 -0.305054)
			(stroke
				(width 0.1)
				(type default)
			)
			(layer "F.Fab")
		)
		(fp_line
			(start -0.67945 0.3048)
			(end -0.67945 -0.305054)
			(stroke
				(width 0.1)
				(type default)
			)
			(layer "F.Fab")
		)
		(fp_line
			(start -0.12065 -0.305054)
			(end -0.12065 -0.2794)
			(stroke
				(width 0.1)
				(type default)
			)
			(layer "F.Fab")
		)
		(fp_line
			(start -0.12065 -0.2794)
			(end 0.12065 -0.2794)
			(stroke
				(width 0.1)
				(type default)
			)
			(layer "F.Fab")
		)
		(fp_line
			(start -0.12065 0.2794)
			(end -0.12065 0.3048)
			(stroke
				(width 0.1)
				(type default)
			)
			(layer "F.Fab")
		)
		(fp_line
			(start -0.12065 0.3048)
			(end -0.67945 0.3048)
			(stroke
				(width 0.1)
				(type default)
			)
			(layer "F.Fab")
		)
		(fp_line
			(start 0.120396 0.2794)
			(end -0.12065 0.2794)
			(stroke
				(width 0.1)
				(type default)
			)
			(layer "F.Fab")
		)
		(fp_line
			(start 0.120396 0.3048)
			(end 0.120396 0.2794)
			(stroke
				(width 0.1)
				(type default)
			)
			(layer "F.Fab")
		)
		(fp_line
			(start 0.12065 -0.3048)
			(end 0.67945 -0.3048)
			(stroke
				(width 0.1)
				(type default)
			)
			(layer "F.Fab")
		)
		(fp_line
			(start 0.12065 -0.2794)
			(end 0.12065 -0.3048)
			(stroke
				(width 0.1)
				(type default)
			)
			(layer "F.Fab")
		)
		(fp_line
			(start 0.67945 -0.3048)
			(end 0.67945 0.3048)
			(stroke
				(width 0.1)
				(type default)
			)
			(layer "F.Fab")
		)
		(fp_line
			(start 0.67945 0.3048)
			(end 0.120396 0.3048)
			(stroke
				(width 0.1)
				(type default)
			)
			(layer "F.Fab")
		)
		(pad "1" smd circle
			(at -0.40005 0)
			(size 0 0)
			(layers "F.Cu" "F.Mask" "F.Paste")
			(net "GPU_3V3IO_RSVD1_FFU_R")
		)
		(pad "2" smd circle
			(at 0.40005 0)
			(size 0 0)
			(layers "F.Cu" "F.Mask" "F.Paste")
			(net "GPU_3V3IO_RSVD1_FFU")
		)
	)
	(footprint ""
		(layer "F.Cu")
		(at 136.870948 -146.205956 180)
		(property "Reference" "C417"
			(at 0 0 180)
			(layer "F.SilkS")
			(hide yes)
			(effects
				(font
					(size 1.27 1.27)
				)
			)
		)
		(property "Value" ""
			(at 0 0 180)
			(layer "F.Fab")
			(effects
				(font
					(size 1.27 1.27)
				)
			)
		)
		(duplicate_pad_numbers_are_jumpers no)
		(fp_line
			(start 0.7874 0.4064)
			(end -0.7874 0.4064)
			(stroke
				(width 0.1524)
				(type default)
			)
			(layer "F.SilkS")
		)
		(fp_line
			(start 0.7874 -0.4064)
			(end 0.7874 0.4064)
			(stroke
				(width 0.1524)
				(type default)
			)
			(layer "F.SilkS")
		)
		(fp_line
			(start -0.7874 0.4064)
			(end -0.7874 -0.4064)
			(stroke
				(width 0.1524)
				(type default)
			)
			(layer "F.SilkS")
		)
		(fp_line
			(start -0.7874 -0.4064)
			(end 0.7874 -0.4064)
			(stroke
				(width 0.1524)
				(type default)
			)
			(layer "F.SilkS")
		)
		(fp_line
			(start 0.67945 0.3048)
			(end 0.120396 0.3048)
			(stroke
				(width 0.1)
				(type default)
			)
			(layer "F.Fab")
		)
		(fp_line
			(start 0.67945 -0.3048)
			(end 0.67945 0.3048)
			(stroke
				(width 0.1)
				(type default)
			)
			(layer "F.Fab")
		)
		(fp_line
			(start 0.12065 -0.2794)
			(end 0.12065 -0.3048)
			(stroke
				(width 0.1)
				(type default)
			)
			(layer "F.Fab")
		)
		(fp_line
			(start 0.12065 -0.3048)
			(end 0.67945 -0.3048)
			(stroke
				(width 0.1)
				(type default)
			)
			(layer "F.Fab")
		)
		(fp_line
			(start 0.120396 0.3048)
			(end 0.120396 0.2794)
			(stroke
				(width 0.1)
				(type default)
			)
			(layer "F.Fab")
		)
		(fp_line
			(start 0.120396 0.2794)
			(end -0.12065 0.2794)
			(stroke
				(width 0.1)
				(type default)
			)
			(layer "F.Fab")
		)
		(fp_line
			(start -0.12065 0.3048)
			(end -0.67945 0.3048)
			(stroke
				(width 0.1)
				(type default)
			)
			(layer "F.Fab")
		)
		(fp_line
			(start -0.12065 0.2794)
			(end -0.12065 0.3048)
			(stroke
				(width 0.1)
				(type default)
			)
			(layer "F.Fab")
		)
		(fp_line
			(start -0.12065 -0.2794)
			(end 0.12065 -0.2794)
			(stroke
				(width 0.1)
				(type default)
			)
			(layer "F.Fab")
		)
		(fp_line
			(start -0.12065 -0.305054)
			(end -0.12065 -0.2794)
			(stroke
				(width 0.1)
				(type default)
			)
			(layer "F.Fab")
		)
		(fp_line
			(start -0.67945 0.3048)
			(end -0.67945 -0.305054)
			(stroke
				(width 0.1)
				(type default)
			)
			(layer "F.Fab")
		)
		(fp_line
			(start -0.67945 -0.305054)
			(end -0.12065 -0.305054)
			(stroke
				(width 0.1)
				(type default)
			)
			(layer "F.Fab")
		)
		(pad "1" smd circle
			(at -0.40005 0 180)
			(size 0 0)
			(layers "F.Cu" "F.Mask" "F.Paste")
			(net "P12V_NIC2_VIN_P")
		)
		(pad "2" smd circle
			(at 0.40005 0 180)
			(size 0 0)
			(layers "F.Cu" "F.Mask" "F.Paste")
			(net "P12V_NIC2_VIN_N")
		)
	)
	(footprint ""
		(layer "F.Cu")
		(at 434.296058 -306.02936 -90)
		(property "Reference" "R6812"
			(at 0 0 270)
			(layer "F.SilkS")
			(hide yes)
			(effects
				(font
					(size 1.27 1.27)
				)
			)
		)
		(property "Value" ""
			(at 0 0 270)
			(layer "F.Fab")
			(effects
				(font
					(size 1.27 1.27)
				)
			)
		)
		(duplicate_pad_numbers_are_jumpers no)
		(fp_line
			(start -0.7874 0.4064)
			(end -0.7874 -0.4064)
			(stroke
				(width 0.1524)
				(type default)
			)
			(layer "F.SilkS")
		)
		(fp_line
			(start 0.7874 0.4064)
			(end -0.7874 0.4064)
			(stroke
				(width 0.1524)
				(type default)
			)
			(layer "F.SilkS")
		)
		(fp_line
			(start -0.7874 -0.4064)
			(end 0.7874 -0.4064)
			(stroke
				(width 0.1524)
				(type default)
			)
			(layer "F.SilkS")
		)
		(fp_line
			(start 0.7874 -0.4064)
			(end 0.7874 0.4064)
			(stroke
				(width 0.1524)
				(type default)
			)
			(layer "F.SilkS")
		)
		(fp_line
			(start -0.67945 0.3048)
			(end -0.67945 -0.305054)
			(stroke
				(width 0.1)
				(type default)
			)
			(layer "F.Fab")
		)
		(fp_line
			(start -0.12065 0.3048)
			(end -0.67945 0.3048)
			(stroke
				(width 0.1)
				(type default)
			)
			(layer "F.Fab")
		)
		(fp_line
			(start 0.120396 0.3048)
			(end 0.120396 0.2794)
			(stroke
				(width 0.1)
				(type default)
			)
			(layer "F.Fab")
		)
		(fp_line
			(start 0.67945 0.3048)
			(end 0.120396 0.3048)
			(stroke
				(width 0.1)
				(type default)
			)
			(layer "F.Fab")
		)
		(fp_line
			(start -0.12065 0.2794)
			(end -0.12065 0.3048)
			(stroke
				(width 0.1)
				(type default)
			)
			(layer "F.Fab")
		)
		(fp_line
			(start 0.120396 0.2794)
			(end -0.12065 0.2794)
			(stroke
				(width 0.1)
				(type default)
			)
			(layer "F.Fab")
		)
		(fp_line
			(start -0.12065 -0.2794)
			(end 0.12065 -0.2794)
			(stroke
				(width 0.1)
				(type default)
			)
			(layer "F.Fab")
		)
		(fp_line
			(start 0.12065 -0.2794)
			(end 0.12065 -0.3048)
			(stroke
				(width 0.1)
				(type default)
			)
			(layer "F.Fab")
		)
		(fp_line
			(start 0.12065 -0.3048)
			(end 0.67945 -0.3048)
			(stroke
				(width 0.1)
				(type default)
			)
			(layer "F.Fab")
		)
		(fp_line
			(start 0.67945 -0.3048)
			(end 0.67945 0.3048)
			(stroke
				(width 0.1)
				(type default)
			)
			(layer "F.Fab")
		)
		(fp_line
			(start -0.67945 -0.305054)
			(end -0.12065 -0.305054)
			(stroke
				(width 0.1)
				(type default)
			)
			(layer "F.Fab")
		)
		(fp_line
			(start -0.12065 -0.305054)
			(end -0.12065 -0.2794)
			(stroke
				(width 0.1)
				(type default)
			)
			(layer "F.Fab")
		)
		(pad "1" smd circle
			(at -0.40005 0 270)
			(size 0 0)
			(layers "F.Cu" "F.Mask" "F.Paste")
			(net "SMB_PEX3_R_SCL")
		)
		(pad "2" smd circle
			(at 0.40005 0 270)
			(size 0 0)
			(layers "F.Cu" "F.Mask" "F.Paste")
			(net "SMB_PEX3_SCL")
		)
	)
	(footprint ""
		(layer "F.Cu")
		(at 447.58991 -72.766682 90)
		(property "Reference" "PR7096"
			(at 0 0 90)
			(layer "F.SilkS")
			(hide yes)
			(effects
				(font
					(size 1.27 1.27)
				)
			)
		)
		(property "Value" ""
			(at 0 0 90)
			(layer "F.Fab")
			(effects
				(font
					(size 1.27 1.27)
				)
			)
		)
		(duplicate_pad_numbers_are_jumpers no)
		(fp_line
			(start 0.7874 -0.4064)
			(end 0.7874 0.4064)
			(stroke
				(width 0.1524)
				(type default)
			)
			(layer "F.SilkS")
		)
		(fp_line
			(start -0.7874 -0.4064)
			(end 0.7874 -0.4064)
			(stroke
				(width 0.1524)
				(type default)
			)
			(layer "F.SilkS")
		)
		(fp_line
			(start 0.7874 0.4064)
			(end -0.7874 0.4064)
			(stroke
				(width 0.1524)
				(type default)
			)
			(layer "F.SilkS")
		)
		(fp_line
			(start -0.7874 0.4064)
			(end -0.7874 -0.4064)
			(stroke
				(width 0.1524)
				(type default)
			)
			(layer "F.SilkS")
		)
		(fp_line
			(start -0.12065 -0.305054)
			(end -0.12065 -0.2794)
			(stroke
				(width 0.1)
				(type default)
			)
			(layer "F.Fab")
		)
		(fp_line
			(start -0.67945 -0.305054)
			(end -0.12065 -0.305054)
			(stroke
				(width 0.1)
				(type default)
			)
			(layer "F.Fab")
		)
		(fp_line
			(start 0.67945 -0.3048)
			(end 0.67945 0.3048)
			(stroke
				(width 0.1)
				(type default)
			)
			(layer "F.Fab")
		)
		(fp_line
			(start 0.12065 -0.3048)
			(end 0.67945 -0.3048)
			(stroke
				(width 0.1)
				(type default)
			)
			(layer "F.Fab")
		)
		(fp_line
			(start 0.12065 -0.2794)
			(end 0.12065 -0.3048)
			(stroke
				(width 0.1)
				(type default)
			)
			(layer "F.Fab")
		)
		(fp_line
			(start -0.12065 -0.2794)
			(end 0.12065 -0.2794)
			(stroke
				(width 0.1)
				(type default)
			)
			(layer "F.Fab")
		)
		(fp_line
			(start 0.120396 0.2794)
			(end -0.12065 0.2794)
			(stroke
				(width 0.1)
				(type default)
			)
			(layer "F.Fab")
		)
		(fp_line
			(start -0.12065 0.2794)
			(end -0.12065 0.3048)
			(stroke
				(width 0.1)
				(type default)
			)
			(layer "F.Fab")
		)
		(fp_line
			(start 0.67945 0.3048)
			(end 0.120396 0.3048)
			(stroke
				(width 0.1)
				(type default)
			)
			(layer "F.Fab")
		)
		(fp_line
			(start 0.120396 0.3048)
			(end 0.120396 0.2794)
			(stroke
				(width 0.1)
				(type default)
			)
			(layer "F.Fab")
		)
		(fp_line
			(start -0.12065 0.3048)
			(end -0.67945 0.3048)
			(stroke
				(width 0.1)
				(type default)
			)
			(layer "F.Fab")
		)
		(fp_line
			(start -0.67945 0.3048)
			(end -0.67945 -0.305054)
			(stroke
				(width 0.1)
				(type default)
			)
			(layer "F.Fab")
		)
		(pad "1" smd circle
			(at -0.40005 0 90)
			(size 0 0)
			(layers "F.Cu" "F.Mask" "F.Paste")
			(net "P12V_SSD15_CO_ILIMIT")
		)
		(pad "2" smd circle
			(at 0.40005 0 90)
			(size 0 0)
			(layers "F.Cu" "F.Mask" "F.Paste")
			(net "GND")
		)
	)
	(footprint ""
		(layer "F.Cu")
		(at 250.111768 -146.263614 180)
		(property "Reference" "C422"
			(at 0 0 180)
			(layer "F.SilkS")
			(hide yes)
			(effects
				(font
					(size 1.27 1.27)
				)
			)
		)
		(property "Value" ""
			(at 0 0 180)
			(layer "F.Fab")
			(effects
				(font
					(size 1.27 1.27)
				)
			)
		)
		(duplicate_pad_numbers_are_jumpers no)
		(fp_line
			(start 0.7874 0.4064)
			(end -0.7874 0.4064)
			(stroke
				(width 0.1524)
				(type default)
			)
			(layer "F.SilkS")
		)
		(fp_line
			(start 0.7874 -0.4064)
			(end 0.7874 0.4064)
			(stroke
				(width 0.1524)
				(type default)
			)
			(layer "F.SilkS")
		)
		(fp_line
			(start -0.7874 0.4064)
			(end -0.7874 -0.4064)
			(stroke
				(width 0.1524)
				(type default)
			)
			(layer "F.SilkS")
		)
		(fp_line
			(start -0.7874 -0.4064)
			(end 0.7874 -0.4064)
			(stroke
				(width 0.1524)
				(type default)
			)
			(layer "F.SilkS")
		)
		(fp_line
			(start 0.67945 0.3048)
			(end 0.120396 0.3048)
			(stroke
				(width 0.1)
				(type default)
			)
			(layer "F.Fab")
		)
		(fp_line
			(start 0.67945 -0.3048)
			(end 0.67945 0.3048)
			(stroke
				(width 0.1)
				(type default)
			)
			(layer "F.Fab")
		)
		(fp_line
			(start 0.12065 -0.2794)
			(end 0.12065 -0.3048)
			(stroke
				(width 0.1)
				(type default)
			)
			(layer "F.Fab")
		)
		(fp_line
			(start 0.12065 -0.3048)
			(end 0.67945 -0.3048)
			(stroke
				(width 0.1)
				(type default)
			)
			(layer "F.Fab")
		)
		(fp_line
			(start 0.120396 0.3048)
			(end 0.120396 0.2794)
			(stroke
				(width 0.1)
				(type default)
			)
			(layer "F.Fab")
		)
		(fp_line
			(start 0.120396 0.2794)
			(end -0.12065 0.2794)
			(stroke
				(width 0.1)
				(type default)
			)
			(layer "F.Fab")
		)
		(fp_line
			(start -0.12065 0.3048)
			(end -0.67945 0.3048)
			(stroke
				(width 0.1)
				(type default)
			)
			(layer "F.Fab")
		)
		(fp_line
			(start -0.12065 0.2794)
			(end -0.12065 0.3048)
			(stroke
				(width 0.1)
				(type default)
			)
			(layer "F.Fab")
		)
		(fp_line
			(start -0.12065 -0.2794)
			(end 0.12065 -0.2794)
			(stroke
				(width 0.1)
				(type default)
			)
			(layer "F.Fab")
		)
		(fp_line
			(start -0.12065 -0.305054)
			(end -0.12065 -0.2794)
			(stroke
				(width 0.1)
				(type default)
			)
			(layer "F.Fab")
		)
		(fp_line
			(start -0.67945 0.3048)
			(end -0.67945 -0.305054)
			(stroke
				(width 0.1)
				(type default)
			)
			(layer "F.Fab")
		)
		(fp_line
			(start -0.67945 -0.305054)
			(end -0.12065 -0.305054)
			(stroke
				(width 0.1)
				(type default)
			)
			(layer "F.Fab")
		)
		(pad "1" smd circle
			(at -0.40005 0 180)
			(size 0 0)
			(layers "F.Cu" "F.Mask" "F.Paste")
			(net "P12V_NIC4_R")
		)
		(pad "2" smd circle
			(at 0.40005 0 180)
			(size 0 0)
			(layers "F.Cu" "F.Mask" "F.Paste")
			(net "GND")
		)
	)
)
